(kicad_pcb
	(version 20260206)
	(generator "pcbnew")
	(generator_version "10.0")
	(general
		(thickness 1.6)
		(legacy_teardrops no)
	)
	(paper "A4")
	(title_block
		(title "04192023_DAF0TMB3IC0_F0TG_MB_C_brd_V02_OCP.brd")
		(comment 1 "Grand Teton / footprints 6488-6495 of 8354")
	)
	(layers
		(0 "F.Cu" signal "TOP")
		(4 "In1.Cu" signal "GND")
		(6 "In2.Cu" signal "IN1")
		(8 "In3.Cu" signal "GND1")
		(10 "In4.Cu" signal "IN2")
		(12 "In5.Cu" signal "GND2")
		(14 "In6.Cu" signal "IN3")
		(16 "In7.Cu" signal "GND3")
		(18 "In8.Cu" signal "VCC")
		(20 "In9.Cu" signal "VCC1")
		(22 "In10.Cu" signal "GND4")
		(24 "In11.Cu" signal "IN4")
		(26 "In12.Cu" signal "GND5")
		(28 "In13.Cu" signal "IN5")
		(30 "In14.Cu" signal "GND6")
		(32 "In15.Cu" signal "IN6")
		(34 "In16.Cu" signal "GND7")
		(2 "B.Cu" signal "BOTTOM")
		(9 "F.Adhes" user "F.Adhesive")
		(11 "B.Adhes" user "B.Adhesive")
		(13 "F.Paste" user "Package Geometry/Pastemask Top")
		(15 "B.Paste" user "Package Geometry/Pastemask Bottom")
		(5 "F.SilkS" user "Ref Des/Silkscreen Top")
		(7 "B.SilkS" user "Ref Des/Silkscreen Bottom")
		(1 "F.Mask" user "Board Geometry/Soldermask Top")
		(3 "B.Mask" user "Board Geometry/Soldermask Bottom")
		(17 "Dwgs.User" user "User.Drawings")
		(19 "Cmts.User" user "User.Comments")
		(21 "Eco1.User" user "User.Eco1")
		(23 "Eco2.User" user "User.Eco2")
		(25 "Edge.Cuts" user "Board Geometry/Outline")
		(27 "Margin" user)
		(31 "F.CrtYd" user "Package Geometry/Place Bound Top")
		(29 "B.CrtYd" user "Package Geometry/Place Bound Bottom")
		(35 "F.Fab" user "Ref Des/Assembly Top")
		(33 "B.Fab" user "Ref Des/Assembly Bottom")
	)
	(footprint ""
		(layer "B.Cu")
		(at 185.862722 3.523234)
		(property "Reference" "J120"
			(at 4.65455 1.527302 270)
			(unlocked yes)
			(layer "B.SilkS")
			(effects
				(font
					(size 0.7874 0.5842)
					(thickness 0.1524)
				)
				(justify left mirror)
			)
		)
		(property "Value" ""
			(at 0 0 0)
			(layer "B.Fab")
			(effects
				(font
					(size 1.27 1.27)
				)
				(justify mirror)
			)
		)
		(duplicate_pad_numbers_are_jumpers no)
		(fp_line
			(start -1.2192 -2.06756)
			(end -1.2192 2.06756)
			(stroke
				(width 0.1524)
				(type default)
			)
			(layer "B.SilkS")
		)
		(fp_line
			(start -1.2192 2.06756)
			(end 1.2192 2.06756)
			(stroke
				(width 0.1524)
				(type default)
			)
			(layer "B.SilkS")
		)
		(fp_line
			(start 1.2192 -2.06756)
			(end -1.2192 -2.06756)
			(stroke
				(width 0.1524)
				(type default)
			)
			(layer "B.SilkS")
		)
		(fp_line
			(start 1.2192 2.06756)
			(end 1.2192 -2.06756)
			(stroke
				(width 0.1524)
				(type default)
			)
			(layer "B.SilkS")
		)
		(pad "" np_thru_hole circle
			(at -3.4671 -1.27 270)
			(size 1.0414 1.0414)
			(drill 1.0414)
			(layers "*.Cu" "*.Mask")
			(clearance 0.381)
			(thermal_gap 0.381)
		)
		(pad "" np_thru_hole circle
			(at -3.4671 1.27 270)
			(size 1.0414 1.0414)
			(drill 1.0414)
			(layers "*.Cu" "*.Mask")
			(clearance 0.381)
			(thermal_gap 0.381)
		)
		(pad "" np_thru_hole circle
			(at 2.8829 -1.27 270)
			(size 1.0414 1.0414)
			(drill 1.0414)
			(layers "*.Cu" "*.Mask")
			(clearance 0.381)
			(thermal_gap 0.381)
		)
		(pad "" np_thru_hole circle
			(at 2.8829 1.27 270)
			(size 1.0414 1.0414)
			(drill 1.0414)
			(layers "*.Cu" "*.Mask")
			(clearance 0.381)
			(thermal_gap 0.381)
		)
		(pad "1" smd rect
			(at -0.8255 -0.249936 270)
			(size 0.3048 0.508)
			(layers "B.Cu" "B.Mask" "B.Paste")
			(net "DELTA_L_85_10INCH_IN5_DN")
		)
		(pad "2" smd rect
			(at -0.8255 0.249936 270)
			(size 0.3048 0.508)
			(layers "B.Cu" "B.Mask" "B.Paste")
			(net "DELTA_L_85_10INCH_IN5_DP")
		)
		(pad "3" smd circle
			(at 0 0 180)
			(size 0 0)
			(layers "B.Cu" "B.Mask" "B.Paste")
			(net "DELTA_L_GND_1")
		)
		(zone
			(layers "F.Cu" "B.Cu" "In1.Cu" "In2.Cu" "In3.Cu" "In4.Cu" "In5.Cu" "In6.Cu"
				"In7.Cu" "In8.Cu" "In9.Cu" "In10.Cu" "In11.Cu" "In12.Cu" "In13.Cu" "In14.Cu"
				"In15.Cu" "In16.Cu"
			)
			(hatch none 0.5)
			(connect_pads
				(clearance 0)
			)
			(min_thickness 0.25)
			(keepout
				(tracks not_allowed)
				(vias allowed)
				(pads allowed)
				(copperpour not_allowed)
				(footprints allowed)
			)
			(placement
				(enabled no)
				(sheetname "")
			)
			(fill
				(thermal_gap 0.5)
				(thermal_bridge_width 0.5)
				(island_removal_mode 0)
			)
			(polygon
				(pts
					(arc
						(start 183.322722 2.253234)
						(mid 181.468522 2.253234)
						(end 183.322722 2.253234)
					)
				)
			)
		)
		(zone
			(layers "F.Cu" "B.Cu" "In1.Cu" "In2.Cu" "In3.Cu" "In4.Cu" "In5.Cu" "In6.Cu"
				"In7.Cu" "In8.Cu" "In9.Cu" "In10.Cu" "In11.Cu" "In12.Cu" "In13.Cu" "In14.Cu"
				"In15.Cu" "In16.Cu"
			)
			(hatch none 0.5)
			(connect_pads
				(clearance 0)
			)
			(min_thickness 0.25)
			(keepout
				(tracks not_allowed)
				(vias allowed)
				(pads allowed)
				(copperpour not_allowed)
				(footprints allowed)
			)
			(placement
				(enabled no)
				(sheetname "")
			)
			(fill
				(thermal_gap 0.5)
				(thermal_bridge_width 0.5)
				(island_removal_mode 0)
			)
			(polygon
				(pts
					(arc
						(start 183.322722 4.793234)
						(mid 181.468522 4.793234)
						(end 183.322722 4.793234)
					)
				)
			)
		)
		(zone
			(layers "F.Cu" "B.Cu" "In1.Cu" "In2.Cu" "In3.Cu" "In4.Cu" "In5.Cu" "In6.Cu"
				"In7.Cu" "In8.Cu" "In9.Cu" "In10.Cu" "In11.Cu" "In12.Cu" "In13.Cu" "In14.Cu"
				"In15.Cu" "In16.Cu"
			)
			(hatch none 0.5)
			(connect_pads
				(clearance 0)
			)
			(min_thickness 0.25)
			(keepout
				(tracks not_allowed)
				(vias allowed)
				(pads allowed)
				(copperpour not_allowed)
				(footprints allowed)
			)
			(placement
				(enabled no)
				(sheetname "")
			)
			(fill
				(thermal_gap 0.5)
				(thermal_bridge_width 0.5)
				(island_removal_mode 0)
			)
			(polygon
				(pts
					(arc
						(start 189.672722 2.253234)
						(mid 187.818522 2.253234)
						(end 189.672722 2.253234)
					)
				)
			)
		)
		(zone
			(layers "F.Cu" "B.Cu" "In1.Cu" "In2.Cu" "In3.Cu" "In4.Cu" "In5.Cu" "In6.Cu"
				"In7.Cu" "In8.Cu" "In9.Cu" "In10.Cu" "In11.Cu" "In12.Cu" "In13.Cu" "In14.Cu"
				"In15.Cu" "In16.Cu"
			)
			(hatch none 0.5)
			(connect_pads
				(clearance 0)
			)
			(min_thickness 0.25)
			(keepout
				(tracks not_allowed)
				(vias allowed)
				(pads allowed)
				(copperpour not_allowed)
				(footprints allowed)
			)
			(placement
				(enabled no)
				(sheetname "")
			)
			(fill
				(thermal_gap 0.5)
				(thermal_bridge_width 0.5)
				(island_removal_mode 0)
			)
			(polygon
				(pts
					(arc
						(start 189.672722 4.793234)
						(mid 187.818522 4.793234)
						(end 189.672722 4.793234)
					)
				)
			)
		)
		(zone
			(layer "B.Cu")
			(hatch none 0.5)
			(connect_pads
				(clearance 0)
			)
			(min_thickness 0.25)
			(keepout
				(tracks not_allowed)
				(vias allowed)
				(pads allowed)
				(copperpour not_allowed)
				(footprints allowed)
			)
			(placement
				(enabled no)
				(sheetname "")
			)
			(fill
				(thermal_gap 0.5)
				(thermal_bridge_width 0.5)
				(island_removal_mode 0)
			)
			(polygon
				(pts
					(xy 184.745122 2.974594) (xy 184.745122 3.070098) (xy 185.342022 3.070098) (xy 185.342022 3.476498)
					(xy 184.745122 3.476498) (xy 184.745122 3.56997) (xy 185.342022 3.56997) (xy 185.342022 3.97637)
					(xy 184.745122 3.97637) (xy 184.745122 4.071874) (xy 185.443622 4.071874) (xy 185.443622 2.974594)
				)
			)
		)
	)
	(footprint ""
		(layer "B.Cu")
		(at 105.196386 -248.479564)
		(property "Reference" "C2319"
			(at 0 0 0)
			(layer "B.SilkS")
			(hide yes)
			(effects
				(font
					(size 1.27 1.27)
				)
				(justify mirror)
			)
		)
		(property "Value" ""
			(at 0 0 0)
			(layer "B.Fab")
			(effects
				(font
					(size 1.27 1.27)
				)
				(justify mirror)
			)
		)
		(duplicate_pad_numbers_are_jumpers no)
		(fp_line
			(start -0.7874 -0.4064)
			(end -0.7874 0.4064)
			(stroke
				(width 0.1524)
				(type default)
			)
			(layer "B.SilkS")
		)
		(fp_line
			(start -0.7874 0.4064)
			(end 0.7874 0.4064)
			(stroke
				(width 0.1524)
				(type default)
			)
			(layer "B.SilkS")
		)
		(fp_line
			(start 0.7874 -0.4064)
			(end -0.7874 -0.4064)
			(stroke
				(width 0.1524)
				(type default)
			)
			(layer "B.SilkS")
		)
		(fp_line
			(start 0.7874 0.4064)
			(end 0.7874 -0.4064)
			(stroke
				(width 0.1524)
				(type default)
			)
			(layer "B.SilkS")
		)
		(fp_line
			(start -0.67945 -0.3048)
			(end -0.67945 0.3048)
			(stroke
				(width 0.1)
				(type default)
			)
			(layer "B.Fab")
		)
		(fp_line
			(start -0.67945 0.3048)
			(end -0.120396 0.3048)
			(stroke
				(width 0.1)
				(type default)
			)
			(layer "B.Fab")
		)
		(fp_line
			(start -0.12065 -0.3048)
			(end -0.67945 -0.3048)
			(stroke
				(width 0.1)
				(type default)
			)
			(layer "B.Fab")
		)
		(fp_line
			(start -0.12065 -0.2794)
			(end -0.12065 -0.3048)
			(stroke
				(width 0.1)
				(type default)
			)
			(layer "B.Fab")
		)
		(fp_line
			(start -0.120396 0.2794)
			(end 0.12065 0.2794)
			(stroke
				(width 0.1)
				(type default)
			)
			(layer "B.Fab")
		)
		(fp_line
			(start -0.120396 0.3048)
			(end -0.120396 0.2794)
			(stroke
				(width 0.1)
				(type default)
			)
			(layer "B.Fab")
		)
		(fp_line
			(start 0.12065 -0.305054)
			(end 0.12065 -0.2794)
			(stroke
				(width 0.1)
				(type default)
			)
			(layer "B.Fab")
		)
		(fp_line
			(start 0.12065 -0.2794)
			(end -0.12065 -0.2794)
			(stroke
				(width 0.1)
				(type default)
			)
			(layer "B.Fab")
		)
		(fp_line
			(start 0.12065 0.2794)
			(end 0.12065 0.3048)
			(stroke
				(width 0.1)
				(type default)
			)
			(layer "B.Fab")
		)
		(fp_line
			(start 0.12065 0.3048)
			(end 0.67945 0.3048)
			(stroke
				(width 0.1)
				(type default)
			)
			(layer "B.Fab")
		)
		(fp_line
			(start 0.67945 -0.305054)
			(end 0.12065 -0.305054)
			(stroke
				(width 0.1)
				(type default)
			)
			(layer "B.Fab")
		)
		(fp_line
			(start 0.67945 0.3048)
			(end 0.67945 -0.305054)
			(stroke
				(width 0.1)
				(type default)
			)
			(layer "B.Fab")
		)
		(pad "1" smd circle
			(at 0.40005 0 180)
			(size 0 0)
			(layers "B.Cu" "B.Mask" "B.Paste")
			(net "PVDDCR_CPU0_P1")
		)
		(pad "2" smd circle
			(at -0.40005 0 180)
			(size 0 0)
			(layers "B.Cu" "B.Mask" "B.Paste")
			(net "GND")
		)
	)
	(footprint ""
		(layer "B.Cu")
		(at 379.018546 -396.393162 -90)
		(property "Reference" "C998"
			(at 0 0 90)
			(layer "B.SilkS")
			(hide yes)
			(effects
				(font
					(size 1.27 1.27)
				)
				(justify mirror)
			)
		)
		(property "Value" ""
			(at 0 0 90)
			(layer "B.Fab")
			(effects
				(font
					(size 1.27 1.27)
				)
				(justify mirror)
			)
		)
		(duplicate_pad_numbers_are_jumpers no)
		(fp_line
			(start -0.299974 0.150114)
			(end 0.299974 0.150114)
			(stroke
				(width 0.1)
				(type default)
			)
			(layer "B.Fab")
		)
		(fp_line
			(start 0.299974 0.150114)
			(end 0.299974 -0.150114)
			(stroke
				(width 0.1)
				(type default)
			)
			(layer "B.Fab")
		)
		(fp_line
			(start -0.299974 -0.150114)
			(end -0.299974 0.150114)
			(stroke
				(width 0.1)
				(type default)
			)
			(layer "B.Fab")
		)
		(fp_line
			(start 0.299974 -0.150114)
			(end -0.299974 -0.150114)
			(stroke
				(width 0.1)
				(type default)
			)
			(layer "B.Fab")
		)
		(pad "1" smd rect
			(at 0.2667 0 90)
			(size 0.3048 0.381)
			(layers "B.Cu" "B.Mask" "B.Paste")
			(net "P1V8_CPU0_RT3_1A")
		)
		(pad "2" smd rect
			(at -0.2667 0 90)
			(size 0.3048 0.381)
			(layers "B.Cu" "B.Mask" "B.Paste")
			(net "GND")
		)
	)
	(footprint ""
		(layer "B.Cu")
		(at 334.099408 -389.97763)
		(property "Reference" "C7013"
			(at 0 0 0)
			(layer "B.SilkS")
			(hide yes)
			(effects
				(font
					(size 1.27 1.27)
				)
				(justify mirror)
			)
		)
		(property "Value" ""
			(at 0 0 0)
			(layer "B.Fab")
			(effects
				(font
					(size 1.27 1.27)
				)
				(justify mirror)
			)
		)
		(duplicate_pad_numbers_are_jumpers no)
		(fp_line
			(start -1.524 -0.762)
			(end -1.524 0.762)
			(stroke
				(width 0.1524)
				(type default)
			)
			(layer "B.SilkS")
		)
		(fp_line
			(start -1.524 0.762)
			(end 1.524 0.762)
			(stroke
				(width 0.1524)
				(type default)
			)
			(layer "B.SilkS")
		)
		(fp_line
			(start 1.524 -0.762)
			(end -1.524 -0.762)
			(stroke
				(width 0.1524)
				(type default)
			)
			(layer "B.SilkS")
		)
		(fp_line
			(start 1.524 0.762)
			(end 1.524 -0.762)
			(stroke
				(width 0.1524)
				(type default)
			)
			(layer "B.SilkS")
		)
		(fp_line
			(start -1.1049 -0.724916)
			(end 1.1049 -0.724916)
			(stroke
				(width 0.1)
				(type default)
			)
			(layer "B.Fab")
		)
		(fp_line
			(start -1.1049 0.724916)
			(end -1.1049 -0.724916)
			(stroke
				(width 0.1)
				(type default)
			)
			(layer "B.Fab")
		)
		(fp_line
			(start 1.1049 -0.724916)
			(end 1.1049 0.724916)
			(stroke
				(width 0.1)
				(type default)
			)
			(layer "B.Fab")
		)
		(fp_line
			(start 1.1049 0.724916)
			(end -1.1049 0.724916)
			(stroke
				(width 0.1)
				(type default)
			)
			(layer "B.Fab")
		)
		(pad "1" smd rect
			(at 0.889 0)
			(size 1.016 1.27)
			(layers "B.Cu" "B.Mask" "B.Paste")
			(net "P0V9_CPU0_RT1_2A")
		)
		(pad "2" smd rect
			(at -0.889 0)
			(size 1.016 1.27)
			(layers "B.Cu" "B.Mask" "B.Paste")
			(net "GND")
		)
	)
	(footprint ""
		(layer "B.Cu")
		(at 305.423316 -428.0916 180)
		(property "Reference" "R1446"
			(at 0 0 0)
			(layer "B.SilkS")
			(hide yes)
			(effects
				(font
					(size 1.27 1.27)
				)
				(justify mirror)
			)
		)
		(property "Value" ""
			(at 0 0 0)
			(layer "B.Fab")
			(effects
				(font
					(size 1.27 1.27)
				)
				(justify mirror)
			)
		)
		(duplicate_pad_numbers_are_jumpers no)
		(fp_line
			(start 0.32512 0.175006)
			(end 0.32512 -0.175006)
			(stroke
				(width 0.1)
				(type default)
			)
			(layer "B.Fab")
		)
		(fp_line
			(start 0.32512 -0.175006)
			(end -0.32512 -0.175006)
			(stroke
				(width 0.1)
				(type default)
			)
			(layer "B.Fab")
		)
		(fp_line
			(start -0.32512 0.175006)
			(end 0.32512 0.175006)
			(stroke
				(width 0.1)
				(type default)
			)
			(layer "B.Fab")
		)
		(fp_line
			(start -0.32512 -0.175006)
			(end -0.32512 0.175006)
			(stroke
				(width 0.1)
				(type default)
			)
			(layer "B.Fab")
		)
		(pad "1" smd rect
			(at 0.2667 0)
			(size 0.3048 0.381)
			(layers "B.Cu" "B.Mask" "B.Paste")
			(net "P1V8_CPU0_RT_1D")
		)
		(pad "2" smd rect
			(at -0.2667 0 180)
			(size 0.3048 0.381)
			(layers "B.Cu" "B.Mask" "B.Paste")
			(net "JTAG_TCK_RT_CPU0_P0")
		)
	)
	(footprint ""
		(layer "B.Cu")
		(at 104.307386 -253.432564)
		(property "Reference" "C2455"
			(at 0 0 0)
			(layer "B.SilkS")
			(hide yes)
			(effects
				(font
					(size 1.27 1.27)
				)
				(justify mirror)
			)
		)
		(property "Value" ""
			(at 0 0 0)
			(layer "B.Fab")
			(effects
				(font
					(size 1.27 1.27)
				)
				(justify mirror)
			)
		)
		(duplicate_pad_numbers_are_jumpers no)
		(fp_line
			(start -0.7874 -0.4064)
			(end -0.7874 0.4064)
			(stroke
				(width 0.1524)
				(type default)
			)
			(layer "B.SilkS")
		)
		(fp_line
			(start -0.7874 0.4064)
			(end 0.7874 0.4064)
			(stroke
				(width 0.1524)
				(type default)
			)
			(layer "B.SilkS")
		)
		(fp_line
			(start 0.7874 -0.4064)
			(end -0.7874 -0.4064)
			(stroke
				(width 0.1524)
				(type default)
			)
			(layer "B.SilkS")
		)
		(fp_line
			(start 0.7874 0.4064)
			(end 0.7874 -0.4064)
			(stroke
				(width 0.1524)
				(type default)
			)
			(layer "B.SilkS")
		)
		(fp_line
			(start -0.67945 -0.3048)
			(end -0.67945 0.3048)
			(stroke
				(width 0.1)
				(type default)
			)
			(layer "B.Fab")
		)
		(fp_line
			(start -0.67945 0.3048)
			(end -0.120396 0.3048)
			(stroke
				(width 0.1)
				(type default)
			)
			(layer "B.Fab")
		)
		(fp_line
			(start -0.12065 -0.3048)
			(end -0.67945 -0.3048)
			(stroke
				(width 0.1)
				(type default)
			)
			(layer "B.Fab")
		)
		(fp_line
			(start -0.12065 -0.2794)
			(end -0.12065 -0.3048)
			(stroke
				(width 0.1)
				(type default)
			)
			(layer "B.Fab")
		)
		(fp_line
			(start -0.120396 0.2794)
			(end 0.12065 0.2794)
			(stroke
				(width 0.1)
				(type default)
			)
			(layer "B.Fab")
		)
		(fp_line
			(start -0.120396 0.3048)
			(end -0.120396 0.2794)
			(stroke
				(width 0.1)
				(type default)
			)
			(layer "B.Fab")
		)
		(fp_line
			(start 0.12065 -0.305054)
			(end 0.12065 -0.2794)
			(stroke
				(width 0.1)
				(type default)
			)
			(layer "B.Fab")
		)
		(fp_line
			(start 0.12065 -0.2794)
			(end -0.12065 -0.2794)
			(stroke
				(width 0.1)
				(type default)
			)
			(layer "B.Fab")
		)
		(fp_line
			(start 0.12065 0.2794)
			(end 0.12065 0.3048)
			(stroke
				(width 0.1)
				(type default)
			)
			(layer "B.Fab")
		)
		(fp_line
			(start 0.12065 0.3048)
			(end 0.67945 0.3048)
			(stroke
				(width 0.1)
				(type default)
			)
			(layer "B.Fab")
		)
		(fp_line
			(start 0.67945 -0.305054)
			(end 0.12065 -0.305054)
			(stroke
				(width 0.1)
				(type default)
			)
			(layer "B.Fab")
		)
		(fp_line
			(start 0.67945 0.3048)
			(end 0.67945 -0.305054)
			(stroke
				(width 0.1)
				(type default)
			)
			(layer "B.Fab")
		)
		(pad "1" smd circle
			(at 0.40005 0 180)
			(size 0 0)
			(layers "B.Cu" "B.Mask" "B.Paste")
			(net "PVDDCR_SOC_P1")
		)
		(pad "2" smd circle
			(at -0.40005 0 180)
			(size 0 0)
			(layers "B.Cu" "B.Mask" "B.Paste")
			(net "GND")
		)
	)
	(footprint ""
		(layer "B.Cu")
		(at 214.122 -339.598)
		(property "Reference" "R913"
			(at 0 0 0)
			(layer "B.SilkS")
			(hide yes)
			(effects
				(font
					(size 1.27 1.27)
				)
				(justify mirror)
			)
		)
		(property "Value" ""
			(at 0 0 0)
			(layer "B.Fab")
			(effects
				(font
					(size 1.27 1.27)
				)
				(justify mirror)
			)
		)
		(duplicate_pad_numbers_are_jumpers no)
		(fp_line
			(start -0.32512 -0.175006)
			(end -0.32512 0.175006)
			(stroke
				(width 0.1)
				(type default)
			)
			(layer "B.Fab")
		)
		(fp_line
			(start -0.32512 0.175006)
			(end 0.32512 0.175006)
			(stroke
				(width 0.1)
				(type default)
			)
			(layer "B.Fab")
		)
		(fp_line
			(start 0.32512 -0.175006)
			(end -0.32512 -0.175006)
			(stroke
				(width 0.1)
				(type default)
			)
			(layer "B.Fab")
		)
		(fp_line
			(start 0.32512 0.175006)
			(end 0.32512 -0.175006)
			(stroke
				(width 0.1)
				(type default)
			)
			(layer "B.Fab")
		)
		(pad "1" smd rect
			(at 0.2667 0 180)
			(size 0.3048 0.381)
			(layers "B.Cu" "B.Mask" "B.Paste")
			(net "SMB_RT_CPU1_P3_R_SCL")
		)
		(pad "2" smd rect
			(at -0.2667 0)
			(size 0.3048 0.381)
			(layers "B.Cu" "B.Mask" "B.Paste")
			(net "SMB_RT_CPU1_P3_R2_SCL")
		)
	)
	(footprint ""
		(layer "B.Cu")
		(at 315.391038 -399.291302 90)
		(property "Reference" "C528"
			(at 0 0 90)
			(layer "B.SilkS")
			(hide yes)
			(effects
				(font
					(size 1.27 1.27)
				)
				(justify mirror)
			)
		)
		(property "Value" ""
			(at 0 0 90)
			(layer "B.Fab")
			(effects
				(font
					(size 1.27 1.27)
				)
				(justify mirror)
			)
		)
		(duplicate_pad_numbers_are_jumpers no)
		(fp_line
			(start 0.299974 -0.150114)
			(end -0.299974 -0.150114)
			(stroke
				(width 0.1)
				(type default)
			)
			(layer "B.Fab")
		)
		(fp_line
			(start -0.299974 -0.150114)
			(end -0.299974 0.150114)
			(stroke
				(width 0.1)
				(type default)
			)
			(layer "B.Fab")
		)
		(fp_line
			(start 0.299974 0.150114)
			(end 0.299974 -0.150114)
			(stroke
				(width 0.1)
				(type default)
			)
			(layer "B.Fab")
		)
		(fp_line
			(start -0.299974 0.150114)
			(end 0.299974 0.150114)
			(stroke
				(width 0.1)
				(type default)
			)
			(layer "B.Fab")
		)
		(pad "1" smd rect
			(at 0.2667 0 270)
			(size 0.3048 0.381)
			(layers "B.Cu" "B.Mask" "B.Paste")
			(net "P0V9_CPU0_RT_2D")
		)
		(pad "2" smd rect
			(at -0.2667 0 270)
			(size 0.3048 0.381)
			(layers "B.Cu" "B.Mask" "B.Paste")
			(net "GND")
		)
	)
)
